(kicad_pcb
	(version 20260206)
	(generator "pcbnew")
	(generator_version "10.0")
	(general
		(thickness 1.6)
		(legacy_teardrops no)
	)
	(paper "A4")
	(title_block
		(title "baseboard — 13948-1b.1110WZS1818.brd")
		(comment 1 "Honey Badger (Wiwynn) / footprints 1141-1148 of 2523")
	)
	(layers
		(0 "F.Cu" signal "TOP")
		(4 "In1.Cu" signal "L2GND")
		(6 "In2.Cu" signal "L3")
		(8 "In3.Cu" signal "L4VCC")
		(10 "In4.Cu" signal "L5VCC")
		(12 "In5.Cu" signal "L6")
		(14 "In6.Cu" signal "L7GND")
		(2 "B.Cu" signal "BOTTOM")
		(9 "F.Adhes" user "F.Adhesive")
		(11 "B.Adhes" user "B.Adhesive")
		(13 "F.Paste" user "Package Geometry/Pastemask Top")
		(15 "B.Paste" user "Package Geometry/Pastemask Bottom")
		(5 "F.SilkS" user "Ref Des/Silkscreen Top")
		(7 "B.SilkS" user "Ref Des/Silkscreen Bottom")
		(1 "F.Mask" user "Board Geometry/Soldermask Top")
		(3 "B.Mask" user "Board Geometry/Soldermask Bottom")
		(17 "Dwgs.User" user "User.Drawings")
		(19 "Cmts.User" user "User.Comments")
		(21 "Eco1.User" user "User.Eco1")
		(23 "Eco2.User" user "User.Eco2")
		(25 "Edge.Cuts" user "Board Geometry/Outline")
		(27 "Margin" user)
		(31 "F.CrtYd" user "Package Geometry/Place Bound Top")
		(29 "B.CrtYd" user "Package Geometry/Place Bound Bottom")
		(35 "F.Fab" user "Ref Des/Assembly Top")
		(33 "B.Fab" user "Ref Des/Assembly Bottom")
	)
	(footprint ""
		(layer "F.Cu")
		(at 12.650216 -214.05088 90)
		(property "Reference" "R624"
			(at 0 0 90)
			(layer "F.SilkS")
			(hide yes)
			(effects
				(font
					(size 1.27 1.27)
				)
			)
		)
		(property "Value" "10KR2F-2-GP"
			(at 0.064008 -3.993896 90)
			(unlocked yes)
			(layer "F.Fab")
			(hide yes)
			(effects
				(font
					(size 1.016 1.016)
					(thickness 0.1524)
				)
			)
		)
		(property "Device Type" "R402H16"
			(at 0.064008 -5.517896 90)
			(unlocked yes)
			(layer "F.Fab")
			(hide yes)
			(effects
				(font
					(size 1.016 1.016)
					(thickness 0.1524)
				)
			)
		)
		(duplicate_pad_numbers_are_jumpers no)
		(fp_line
			(start 0.508 -0.9398)
			(end -0.508 -0.9398)
			(stroke
				(width 0.1524)
				(type default)
			)
			(layer "F.SilkS")
		)
		(fp_line
			(start -0.508 -0.9398)
			(end -0.508 0.9398)
			(stroke
				(width 0.1524)
				(type default)
			)
			(layer "F.SilkS")
		)
		(fp_rect
			(start -0.508 0.9398)
			(end 0.508 -0.9398)
			(stroke
				(width 0)
				(type default)
			)
			(fill no)
			(layer "F.CrtYd")
		)
		(fp_rect
			(start -0.508 0.9398)
			(end 0.508 -0.9398)
			(stroke
				(width 0)
				(type default)
			)
			(fill no)
			(layer "F.Fab")
		)
		(pad "1" smd custom
			(at 0 -0.4445 90)
			(size 0.1397 0.1397)
			(layers "F.Cu" "F.Mask" "F.Paste")
			(net "PCIE_MATED#")
			(options
				(clearance outline)
				(anchor circle)
			)
			(primitives
				(gr_poly
					(pts
						(arc
							(start -0.1778 -0.2794)
							(mid -0.249642 -0.249642)
							(end -0.2794 -0.1778)
						)
						(arc
							(start -0.2794 0.1778)
							(mid -0.249642 0.249642)
							(end -0.1778 0.2794)
						)
						(arc
							(start 0.1778 0.2794)
							(mid 0.249642 0.249642)
							(end 0.2794 0.1778)
						)
						(arc
							(start 0.2794 -0.1778)
							(mid 0.249642 -0.249642)
							(end 0.1778 -0.2794)
						)
					)
					(width 0)
					(fill yes)
				)
			)
		)
		(pad "2" smd custom
			(at 0 0.4445 90)
			(size 0.1397 0.1397)
			(layers "F.Cu" "F.Mask" "F.Paste")
			(net "P3V3_STBY")
			(options
				(clearance outline)
				(anchor circle)
			)
			(primitives
				(gr_poly
					(pts
						(arc
							(start -0.1778 -0.2794)
							(mid -0.249642 -0.249642)
							(end -0.2794 -0.1778)
						)
						(arc
							(start -0.2794 0.1778)
							(mid -0.249642 0.249642)
							(end -0.1778 0.2794)
						)
						(arc
							(start 0.1778 0.2794)
							(mid 0.249642 0.249642)
							(end 0.2794 0.1778)
						)
						(arc
							(start 0.2794 -0.1778)
							(mid 0.249642 -0.249642)
							(end 0.1778 -0.2794)
						)
					)
					(width 0)
					(fill yes)
				)
			)
		)
	)
	(footprint ""
		(layer "F.Cu")
		(at 184.339992 -46.355)
		(property "Reference" "R525"
			(at 0 0 0)
			(layer "F.SilkS")
			(hide yes)
			(effects
				(font
					(size 1.27 1.27)
				)
			)
		)
		(property "Value" "10KR2F-2-GP"
			(at 0.064008 -3.993896 0)
			(unlocked yes)
			(layer "F.Fab")
			(hide yes)
			(effects
				(font
					(size 1.016 1.016)
					(thickness 0.1524)
				)
			)
		)
		(property "Device Type" "R402H16"
			(at 0.064008 -5.517896 0)
			(unlocked yes)
			(layer "F.Fab")
			(hide yes)
			(effects
				(font
					(size 1.016 1.016)
					(thickness 0.1524)
				)
			)
		)
		(duplicate_pad_numbers_are_jumpers no)
		(fp_line
			(start -0.508 -0.9398)
			(end -0.508 0.9398)
			(stroke
				(width 0.1524)
				(type default)
			)
			(layer "F.SilkS")
		)
		(fp_line
			(start 0.508 -0.9398)
			(end -0.508 -0.9398)
			(stroke
				(width 0.1524)
				(type default)
			)
			(layer "F.SilkS")
		)
		(fp_rect
			(start -0.508 0.9398)
			(end 0.508 -0.9398)
			(stroke
				(width 0)
				(type default)
			)
			(fill no)
			(layer "F.CrtYd")
		)
		(fp_rect
			(start -0.508 0.9398)
			(end 0.508 -0.9398)
			(stroke
				(width 0)
				(type default)
			)
			(fill no)
			(layer "F.Fab")
		)
		(pad "1" smd custom
			(at 0 -0.4445)
			(size 0.1397 0.1397)
			(layers "F.Cu" "F.Mask" "F.Paste")
			(net "P3V3_STBY")
			(options
				(clearance outline)
				(anchor circle)
			)
			(primitives
				(gr_poly
					(pts
						(arc
							(start -0.1778 -0.2794)
							(mid -0.249642 -0.249642)
							(end -0.2794 -0.1778)
						)
						(arc
							(start -0.2794 0.1778)
							(mid -0.249642 0.249642)
							(end -0.1778 0.2794)
						)
						(arc
							(start 0.1778 0.2794)
							(mid 0.249642 0.249642)
							(end 0.2794 0.1778)
						)
						(arc
							(start 0.2794 -0.1778)
							(mid 0.249642 -0.249642)
							(end 0.1778 -0.2794)
						)
					)
					(width 0)
					(fill yes)
				)
			)
		)
		(pad "2" smd custom
			(at 0 0.4445)
			(size 0.1397 0.1397)
			(layers "F.Cu" "F.Mask" "F.Paste")
			(net "PRSNT_MSB_A1")
			(options
				(clearance outline)
				(anchor circle)
			)
			(primitives
				(gr_poly
					(pts
						(arc
							(start -0.1778 -0.2794)
							(mid -0.249642 -0.249642)
							(end -0.2794 -0.1778)
						)
						(arc
							(start -0.2794 0.1778)
							(mid -0.249642 0.249642)
							(end -0.1778 0.2794)
						)
						(arc
							(start 0.1778 0.2794)
							(mid 0.249642 0.249642)
							(end 0.2794 0.1778)
						)
						(arc
							(start 0.2794 -0.1778)
							(mid 0.249642 -0.249642)
							(end 0.1778 -0.2794)
						)
					)
					(width 0)
					(fill yes)
				)
			)
		)
	)
	(footprint ""
		(layer "F.Cu")
		(at 343.945718 -146.027648 -90)
		(property "Reference" "TP167"
			(at 0 0 270)
			(layer "F.SilkS")
			(hide yes)
			(effects
				(font
					(size 1.27 1.27)
				)
			)
		)
		(property "Value" "TPAD28"
			(at 0.0127 -1.8034 270)
			(unlocked yes)
			(layer "F.Fab")
			(hide yes)
			(effects
				(font
					(size 1.016 1.016)
					(thickness 0.1524)
				)
			)
		)
		(property "Device Type" "TPAD28"
			(at 0.0127 -3.3274 270)
			(unlocked yes)
			(layer "F.Fab")
			(hide yes)
			(effects
				(font
					(size 1.016 1.016)
					(thickness 0.1524)
				)
			)
		)
		(duplicate_pad_numbers_are_jumpers no)
		(fp_poly
			(pts
				(arc
					(start 0 -0.3556)
					(mid 0 0.3556)
					(end 0 -0.3556)
				)
			)
			(stroke
				(width 0)
				(type default)
			)
			(fill no)
			(layer "F.CrtYd")
		)
		(fp_poly
			(pts
				(arc
					(start 0 -0.6096)
					(mid 0 0.6096)
					(end 0 -0.6096)
				)
			)
			(stroke
				(width 0)
				(type default)
			)
			(fill no)
			(layer "F.Fab")
		)
		(pad "1" smd circle
			(at 0 0 270)
			(size 0.7112 0.7112)
			(layers "F.Cu" "F.Mask" "F.Paste")
			(net "PLLFILT")
		)
	)
	(footprint ""
		(layer "F.Cu")
		(at 14.682216 -220.52788 -90)
		(property "Reference" "SR299"
			(at 0 0 270)
			(layer "F.SilkS")
			(hide yes)
			(effects
				(font
					(size 1.27 1.27)
				)
			)
		)
		(property "Value" "0R2J-2-GP"
			(at 0.064008 -3.993896 270)
			(unlocked yes)
			(layer "F.Fab")
			(hide yes)
			(effects
				(font
					(size 1.016 1.016)
					(thickness 0.1524)
				)
			)
		)
		(property "Device Type" "R402H16"
			(at 0.064008 -5.517896 270)
			(unlocked yes)
			(layer "F.Fab")
			(hide yes)
			(effects
				(font
					(size 1.016 1.016)
					(thickness 0.1524)
				)
			)
		)
		(duplicate_pad_numbers_are_jumpers no)
		(fp_line
			(start -0.508 -0.9398)
			(end -0.508 0.9398)
			(stroke
				(width 0.1524)
				(type default)
			)
			(layer "F.SilkS")
		)
		(fp_line
			(start 0.508 -0.9398)
			(end -0.508 -0.9398)
			(stroke
				(width 0.1524)
				(type default)
			)
			(layer "F.SilkS")
		)
		(fp_rect
			(start -0.508 0.9398)
			(end 0.508 -0.9398)
			(stroke
				(width 0)
				(type default)
			)
			(fill no)
			(layer "F.CrtYd")
		)
		(fp_rect
			(start -0.508 0.9398)
			(end 0.508 -0.9398)
			(stroke
				(width 0)
				(type default)
			)
			(fill no)
			(layer "F.Fab")
		)
		(pad "1" smd custom
			(at 0 -0.4445 270)
			(size 0.1397 0.1397)
			(layers "F.Cu" "F.Mask" "F.Paste")
			(net "PWR_SDA")
			(options
				(clearance outline)
				(anchor circle)
			)
			(primitives
				(gr_poly
					(pts
						(arc
							(start -0.1778 -0.2794)
							(mid -0.249642 -0.249642)
							(end -0.2794 -0.1778)
						)
						(arc
							(start -0.2794 0.1778)
							(mid -0.249642 0.249642)
							(end -0.1778 0.2794)
						)
						(arc
							(start 0.1778 0.2794)
							(mid 0.249642 0.249642)
							(end 0.2794 0.1778)
						)
						(arc
							(start 0.2794 -0.1778)
							(mid 0.249642 -0.249642)
							(end 0.1778 -0.2794)
						)
					)
					(width 0)
					(fill yes)
				)
			)
		)
		(pad "2" smd custom
			(at 0 0.4445 270)
			(size 0.1397 0.1397)
			(layers "F.Cu" "F.Mask" "F.Paste")
			(net "BMC_IOEXP_SDA_10")
			(options
				(clearance outline)
				(anchor circle)
			)
			(primitives
				(gr_poly
					(pts
						(arc
							(start -0.1778 -0.2794)
							(mid -0.249642 -0.249642)
							(end -0.2794 -0.1778)
						)
						(arc
							(start -0.2794 0.1778)
							(mid -0.249642 0.249642)
							(end -0.1778 0.2794)
						)
						(arc
							(start 0.1778 0.2794)
							(mid 0.249642 0.249642)
							(end 0.2794 0.1778)
						)
						(arc
							(start 0.2794 -0.1778)
							(mid 0.249642 -0.249642)
							(end 0.1778 -0.2794)
						)
					)
					(width 0)
					(fill yes)
				)
			)
		)
	)
	(footprint ""
		(layer "F.Cu")
		(at 83.18119 -55.466488 90)
		(property "Reference" "SC922"
			(at 0 0 90)
			(layer "F.SilkS")
			(hide yes)
			(effects
				(font
					(size 1.27 1.27)
				)
			)
		)
		(property "Value" "SCD1U6D3V1KX-GP"
			(at -2.8321 -1.7399 90)
			(unlocked yes)
			(layer "F.Fab")
			(hide yes)
			(effects
				(font
					(size 1.016 1.016)
					(thickness 0.1524)
				)
			)
		)
		(property "Device Type" "C0201H13"
			(at -2.8321 -3.2639 90)
			(unlocked yes)
			(layer "F.Fab")
			(hide yes)
			(effects
				(font
					(size 1.016 1.016)
					(thickness 0.1524)
				)
			)
		)
		(duplicate_pad_numbers_are_jumpers no)
		(fp_rect
			(start -0.2794 0.6477)
			(end 0.2794 -0.6477)
			(stroke
				(width 0)
				(type default)
			)
			(fill no)
			(layer "F.CrtYd")
		)
		(fp_rect
			(start -0.2794 0.6477)
			(end 0.2794 -0.6477)
			(stroke
				(width 0)
				(type default)
			)
			(fill no)
			(layer "F.Fab")
		)
		(pad "1" smd custom
			(at 0 -0.2794 90)
			(size 0.0762 0.0762)
			(layers "F.Cu" "F.Mask" "F.Paste")
			(net "SYS_PLL_VDD")
			(options
				(clearance outline)
				(anchor circle)
			)
			(primitives
				(gr_poly
					(pts
						(arc
							(start 0.1524 -0.127)
							(mid 0.137521 -0.162921)
							(end 0.1016 -0.1778)
						)
						(arc
							(start -0.1016 -0.1778)
							(mid -0.137521 -0.162921)
							(end -0.1524 -0.127)
						)
						(arc
							(start -0.1524 0.127)
							(mid -0.137521 0.162921)
							(end -0.1016 0.1778)
						)
						(arc
							(start 0.1016 0.1778)
							(mid 0.137521 0.162921)
							(end 0.1524 0.127)
						)
					)
					(width 0)
					(fill yes)
				)
			)
		)
		(pad "2" smd custom
			(at 0 0.2794 90)
			(size 0.0762 0.0762)
			(layers "F.Cu" "F.Mask" "F.Paste")
			(net "GND")
			(options
				(clearance outline)
				(anchor circle)
			)
			(primitives
				(gr_poly
					(pts
						(arc
							(start 0.1524 -0.127)
							(mid 0.137521 -0.162921)
							(end 0.1016 -0.1778)
						)
						(arc
							(start -0.1016 -0.1778)
							(mid -0.137521 -0.162921)
							(end -0.1524 -0.127)
						)
						(arc
							(start -0.1524 0.127)
							(mid -0.137521 0.162921)
							(end -0.1016 0.1778)
						)
						(arc
							(start 0.1016 0.1778)
							(mid 0.137521 0.162921)
							(end 0.1524 0.127)
						)
					)
					(width 0)
					(fill yes)
				)
			)
		)
	)
	(footprint ""
		(layer "F.Cu")
		(at 179.324 -15.113 90)
		(property "Reference" "R203"
			(at 0 0 90)
			(layer "F.SilkS")
			(hide yes)
			(effects
				(font
					(size 1.27 1.27)
				)
			)
		)
		(property "Value" "0R2J-2-GP"
			(at 0.064008 -3.993896 90)
			(unlocked yes)
			(layer "F.Fab")
			(hide yes)
			(effects
				(font
					(size 1.016 1.016)
					(thickness 0.1524)
				)
			)
		)
		(property "Device Type" "R402H16"
			(at 0.064008 -5.517896 90)
			(unlocked yes)
			(layer "F.Fab")
			(hide yes)
			(effects
				(font
					(size 1.016 1.016)
					(thickness 0.1524)
				)
			)
		)
		(duplicate_pad_numbers_are_jumpers no)
		(fp_line
			(start 0.508 -0.9398)
			(end -0.508 -0.9398)
			(stroke
				(width 0.1524)
				(type default)
			)
			(layer "F.SilkS")
		)
		(fp_line
			(start -0.508 -0.9398)
			(end -0.508 0.9398)
			(stroke
				(width 0.1524)
				(type default)
			)
			(layer "F.SilkS")
		)
		(fp_rect
			(start -0.508 0.9398)
			(end 0.508 -0.9398)
			(stroke
				(width 0)
				(type default)
			)
			(fill no)
			(layer "F.CrtYd")
		)
		(fp_rect
			(start -0.508 0.9398)
			(end 0.508 -0.9398)
			(stroke
				(width 0)
				(type default)
			)
			(fill no)
			(layer "F.Fab")
		)
		(pad "1" smd custom
			(at 0 -0.4445 90)
			(size 0.1397 0.1397)
			(layers "F.Cu" "F.Mask" "F.Paste")
			(net "GND")
			(options
				(clearance outline)
				(anchor circle)
			)
			(primitives
				(gr_poly
					(pts
						(arc
							(start -0.1778 -0.2794)
							(mid -0.249642 -0.249642)
							(end -0.2794 -0.1778)
						)
						(arc
							(start -0.2794 0.1778)
							(mid -0.249642 0.249642)
							(end -0.1778 0.2794)
						)
						(arc
							(start 0.1778 0.2794)
							(mid 0.249642 0.249642)
							(end 0.2794 0.1778)
						)
						(arc
							(start 0.2794 -0.1778)
							(mid 0.249642 -0.249642)
							(end 0.1778 -0.2794)
						)
					)
					(width 0)
					(fill yes)
				)
			)
		)
		(pad "2" smd custom
			(at 0 0.4445 90)
			(size 0.1397 0.1397)
			(layers "F.Cu" "F.Mask" "F.Paste")
			(net "TEMP_SENSOR_C")
			(options
				(clearance outline)
				(anchor circle)
			)
			(primitives
				(gr_poly
					(pts
						(arc
							(start -0.1778 -0.2794)
							(mid -0.249642 -0.249642)
							(end -0.2794 -0.1778)
						)
						(arc
							(start -0.2794 0.1778)
							(mid -0.249642 0.249642)
							(end -0.1778 0.2794)
						)
						(arc
							(start 0.1778 0.2794)
							(mid 0.249642 0.249642)
							(end 0.2794 0.1778)
						)
						(arc
							(start 0.2794 -0.1778)
							(mid 0.249642 -0.249642)
							(end 0.1778 -0.2794)
						)
					)
					(width 0)
					(fill yes)
				)
			)
		)
	)
	(footprint ""
		(layer "F.Cu")
		(at 315.849 -172.466)
		(property "Reference" "TP173"
			(at 0 0 0)
			(layer "F.SilkS")
			(hide yes)
			(effects
				(font
					(size 1.27 1.27)
				)
			)
		)
		(property "Value" "TPAD28"
			(at -0.0127 -1.6637 0)
			(unlocked yes)
			(layer "F.Fab")
			(hide yes)
			(effects
				(font
					(size 1.016 1.016)
					(thickness 0.1524)
				)
			)
		)
		(property "Device Type" "TPAD28"
			(at -0.0127 -3.1877 0)
			(unlocked yes)
			(layer "F.Fab")
			(hide yes)
			(effects
				(font
					(size 1.016 1.016)
					(thickness 0.1524)
				)
			)
		)
		(duplicate_pad_numbers_are_jumpers no)
		(fp_poly
			(pts
				(arc
					(start 0.3556 0)
					(mid -0.3556 0)
					(end 0.3556 0)
				)
			)
			(stroke
				(width 0)
				(type default)
			)
			(fill no)
			(layer "F.CrtYd")
		)
		(fp_poly
			(pts
				(arc
					(start 0.6096 0)
					(mid -0.6096 0)
					(end 0.6096 0)
				)
			)
			(stroke
				(width 0)
				(type default)
			)
			(fill no)
			(layer "F.Fab")
		)
		(pad "1" smd circle
			(at 0 0)
			(size 0.7112 0.7112)
			(layers "F.Cu" "F.Mask" "F.Paste")
			(net "JTAG_BMC_TDI")
		)
	)
	(footprint ""
		(layer "F.Cu")
		(at 87.992966 -84.328 180)
		(property "Reference" "SC1157"
			(at 0 0 180)
			(layer "F.SilkS")
			(hide yes)
			(effects
				(font
					(size 1.27 1.27)
				)
			)
		)
		(property "Value" "SCD1U6D3V1KX-GP"
			(at -2.8321 -1.7399 180)
			(unlocked yes)
			(layer "F.Fab")
			(hide yes)
			(effects
				(font
					(size 1.016 1.016)
					(thickness 0.1524)
				)
			)
		)
		(property "Device Type" "C0201H13"
			(at -2.8321 -3.2639 180)
			(unlocked yes)
			(layer "F.Fab")
			(hide yes)
			(effects
				(font
					(size 1.016 1.016)
					(thickness 0.1524)
				)
			)
		)
		(duplicate_pad_numbers_are_jumpers no)
		(fp_rect
			(start -0.2794 0.6477)
			(end 0.2794 -0.6477)
			(stroke
				(width 0)
				(type default)
			)
			(fill no)
			(layer "F.CrtYd")
		)
		(fp_rect
			(start -0.2794 0.6477)
			(end 0.2794 -0.6477)
			(stroke
				(width 0)
				(type default)
			)
			(fill no)
			(layer "F.Fab")
		)
		(pad "1" smd custom
			(at 0 -0.2794 180)
			(size 0.0762 0.0762)
			(layers "F.Cu" "F.Mask" "F.Paste")
			(net "PLLDDR_VDDA18")
			(options
				(clearance outline)
				(anchor circle)
			)
			(primitives
				(gr_poly
					(pts
						(arc
							(start 0.1524 -0.127)
							(mid 0.137521 -0.162921)
							(end 0.1016 -0.1778)
						)
						(arc
							(start -0.1016 -0.1778)
							(mid -0.137521 -0.162921)
							(end -0.1524 -0.127)
						)
						(arc
							(start -0.1524 0.127)
							(mid -0.137521 0.162921)
							(end -0.1016 0.1778)
						)
						(arc
							(start 0.1016 0.1778)
							(mid 0.137521 0.162921)
							(end 0.1524 0.127)
						)
					)
					(width 0)
					(fill yes)
				)
			)
		)
		(pad "2" smd custom
			(at 0 0.2794 180)
			(size 0.0762 0.0762)
			(layers "F.Cu" "F.Mask" "F.Paste")
			(net "GND")
			(options
				(clearance outline)
				(anchor circle)
			)
			(primitives
				(gr_poly
					(pts
						(arc
							(start 0.1524 -0.127)
							(mid 0.137521 -0.162921)
							(end 0.1016 -0.1778)
						)
						(arc
							(start -0.1016 -0.1778)
							(mid -0.137521 -0.162921)
							(end -0.1524 -0.127)
						)
						(arc
							(start -0.1524 0.127)
							(mid -0.137521 0.162921)
							(end -0.1016 0.1778)
						)
						(arc
							(start 0.1016 0.1778)
							(mid 0.137521 0.162921)
							(end 0.1524 0.127)
						)
					)
					(width 0)
					(fill yes)
				)
			)
		)
	)
)
